# S9S_MB_2U (Grand Teton) — schematic netlist excerpt (pin names and nets, part order shuffled) for the footprints in the layout excerpt that follows; sources: Cadence DE-HDL packaged netlist, KiCad conversion of 03242023_DA0F0TMBIJ0_F0T_Motherboard_J_brd_V01_OCP.brd

PU300  MAX15090BEWIT  MAX15090BEWI+T EMPTY  pkg BGA28_0-5_3-525X2-065  page 242
  ISENSE  = P12V_SCM_SENSE
  VCC  = P12V_SCM_VCC
  IN_A3  = P12V_AUX
  OUT_A4  = P12V_SCM_R
  IN_A5  = P12V_AUX
  GATE  = P12V_SCM_GATE
  CDLY  = GND
  CB  = P12V_SCM_CB
  GND_B2  = GND
  IN_B3  = P12V_AUX
  OUT_B4  = P12V_SCM_R
  IN_B5  = P12V_AUX
  OUT_B6  = P12V_SCM_R
  \en#\  = GND
  GND_C1  = GND
  GND_C2  = GND
  IN_C3  = P12V_AUX
  OUT_C4  = P12V_SCM_R
  IN_C5  = P12V_AUX
  OUT_C6  = P12V_SCM_R
  \fault#\  = P12V_SCM_FAULT_N
  REG  = P12V_SCM_REG
  UV  = P12V_SCM_UV
  OV  = P12V_SCM_OV
  OUT_D4  = P12V_SCM_R
  IN_D5  = P12V_AUX
  OUT_D6  = P12V_SCM_R
  PG  = P12V_SCM_PWRGD

(kicad_pcb
	(version 20260206)
	(generator "pcbnew")
	(generator_version "10.0")
	(general
		(thickness 1.6)
		(legacy_teardrops no)
	)
	(paper "A4")
	(title_block
		(title "03242023_DA0F0TMBIJ0_F0T_Motherboard_J_brd_V01_OCP.brd")
		(comment 1 "Grand Teton / footprints 672-672 of 6105")
	)
	(layers
		(0 "F.Cu" signal "TOP")
		(4 "In1.Cu" signal "GND")
		(6 "In2.Cu" signal "IN1")
		(8 "In3.Cu" signal "GND1")
		(10 "In4.Cu" signal "IN2")
		(12 "In5.Cu" signal "GND2")
		(14 "In6.Cu" signal "IN3")
		(16 "In7.Cu" signal "GND3")
		(18 "In8.Cu" signal "VCC")
		(20 "In9.Cu" signal "VCC1")
		(22 "In10.Cu" signal "GND4")
		(24 "In11.Cu" signal "IN4")
		(26 "In12.Cu" signal "GND5")
		(28 "In13.Cu" signal "IN5")
		(30 "In14.Cu" signal "GND6")
		(32 "In15.Cu" signal "IN6")
		(34 "In16.Cu" signal "GND7")
		(2 "B.Cu" signal "BOTTOM")
		(9 "F.Adhes" user "F.Adhesive")
		(11 "B.Adhes" user "B.Adhesive")
		(13 "F.Paste" user "Package Geometry/Pastemask Top")
		(15 "B.Paste" user "Package Geometry/Pastemask Bottom")
		(5 "F.SilkS" user "Ref Des/Silkscreen Top")
		(7 "B.SilkS" user "Ref Des/Silkscreen Bottom")
		(1 "F.Mask" user "Board Geometry/Soldermask Top")
		(3 "B.Mask" user "Board Geometry/Soldermask Bottom")
		(17 "Dwgs.User" user "User.Drawings")
		(19 "Cmts.User" user "User.Comments")
		(21 "Eco1.User" user "User.Eco1")
		(23 "Eco2.User" user "User.Eco2")
		(25 "Edge.Cuts" user "Board Geometry/Outline")
		(27 "Margin" user)
		(31 "F.CrtYd" user "Package Geometry/Place Bound Top")
		(29 "B.CrtYd" user "Package Geometry/Place Bound Bottom")
		(35 "F.Fab" user "Ref Des/Assembly Top")
		(33 "B.Fab" user "Ref Des/Assembly Bottom")
	)
	(footprint ""
		(layer "F.Cu")
		(at 189.738762 -25.643332)
		(property "Reference" "PU300"
			(at -6.880352 -3.665982 0)
			(unlocked yes)
			(layer "F.SilkS")
			(effects
				(font
					(size 0.7874 0.5842)
					(thickness 0.1524)
				)
				(justify left)
			)
		)
		(property "Value" ""
			(at 0 0 0)
			(layer "F.Fab")
			(effects
				(font
					(size 1.27 1.27)
				)
			)
		)
		(duplicate_pad_numbers_are_jumpers no)
		(fp_line
			(start -1.774952 -1.039876)
			(end -1.774952 1.039876)
			(stroke
				(width 0.1524)
				(type default)
			)
			(layer "F.SilkS")
		)
		(fp_line
			(start -1.774952 1.039876)
			(end 1.774952 1.039876)
			(stroke
				(width 0.1524)
				(type default)
			)
			(layer "F.SilkS")
		)
		(fp_line
			(start 1.774952 -1.039876)
			(end -1.774952 -1.039876)
			(stroke
				(width 0.1524)
				(type default)
			)
			(layer "F.SilkS")
		)
		(fp_line
			(start 1.774952 1.039876)
			(end 1.774952 -1.039876)
			(stroke
				(width 0.1524)
				(type default)
			)
			(layer "F.SilkS")
		)
		(fp_poly
			(pts
				(xy -1.769872 -1.039876) (xy -1.769872 -0.249936) (xy -2.531872 -0.249936) (xy -2.531872 -1.801876)
				(xy -0.999998 -1.801876) (xy -0.999998 -1.039876)
			)
			(stroke
				(width 0)
				(type default)
			)
			(fill yes)
			(layer "F.SilkS")
		)
		(fp_line
			(start -1.769872 -1.039876)
			(end -1.769872 1.039876)
			(stroke
				(width 0.1)
				(type default)
			)
			(layer "F.Fab")
		)
		(fp_line
			(start -1.769872 1.039876)
			(end 1.769872 1.039876)
			(stroke
				(width 0.1)
				(type default)
			)
			(layer "F.Fab")
		)
		(fp_line
			(start 1.769872 -1.039876)
			(end -1.769872 -1.039876)
			(stroke
				(width 0.1)
				(type default)
			)
			(layer "F.Fab")
		)
		(fp_line
			(start 1.769872 1.039876)
			(end 1.769872 -1.039876)
			(stroke
				(width 0.1)
				(type default)
			)
			(layer "F.Fab")
		)
		(fp_poly
			(pts
				(xy -1.769872 -1.039876) (xy -0.999998 -1.039876) (xy -0.999998 -1.801876) (xy -2.531872 -1.801876)
				(xy -2.531872 -0.249936) (xy -1.769872 -0.249936)
			)
			(stroke
				(width 0)
				(type default)
			)
			(fill yes)
			(layer "F.Fab")
		)
		(pad "A1" smd circle
			(at -1.500124 -0.750062)
			(size 0.2286 0.2286)
			(layers "F.Cu" "F.Mask" "F.Paste")
			(net "P12V_SCM_SENSE")
		)
		(pad "A2" smd circle
			(at -0.999998 -0.750062)
			(size 0.2286 0.2286)
			(layers "F.Cu" "F.Mask" "F.Paste")
			(net "P12V_SCM_VCC")
		)
		(pad "A3" smd circle
			(at -0.499872 -0.750062)
			(size 0.2286 0.2286)
			(layers "F.Cu" "F.Mask" "F.Paste")
			(net "P12V_AUX")
		)
		(pad "A4" smd circle
			(at 0 -0.750062)
			(size 0.2286 0.2286)
			(layers "F.Cu" "F.Mask" "F.Paste")
			(net "P12V_SCM_R")
		)
		(pad "A5" smd circle
			(at 0.499872 -0.750062)
			(size 0.2286 0.2286)
			(layers "F.Cu" "F.Mask" "F.Paste")
			(net "P12V_AUX")
		)
		(pad "A6" smd circle
			(at 0.999998 -0.750062)
			(size 0.2286 0.2286)
			(layers "F.Cu" "F.Mask" "F.Paste")
			(net "P12V_SCM_GATE")
		)
		(pad "A7" smd circle
			(at 1.500124 -0.750062)
			(size 0.2286 0.2286)
			(layers "F.Cu" "F.Mask" "F.Paste")
			(net "GND")
		)
		(pad "B1" smd circle
			(at -1.500124 -0.249936)
			(size 0.2286 0.2286)
			(layers "F.Cu" "F.Mask" "F.Paste")
			(net "P12V_SCM_CB")
		)
		(pad "B2" smd circle
			(at -0.999998 -0.249936)
			(size 0.2286 0.2286)
			(layers "F.Cu" "F.Mask" "F.Paste")
			(net "GND")
		)
		(pad "B3" smd circle
			(at -0.499872 -0.249936)
			(size 0.2286 0.2286)
			(layers "F.Cu" "F.Mask" "F.Paste")
			(net "P12V_AUX")
		)
		(pad "B4" smd circle
			(at 0 -0.249936)
			(size 0.2286 0.2286)
			(layers "F.Cu" "F.Mask" "F.Paste")
			(net "P12V_SCM_R")
		)
		(pad "B5" smd circle
			(at 0.499872 -0.249936)
			(size 0.2286 0.2286)
			(layers "F.Cu" "F.Mask" "F.Paste")
			(net "P12V_AUX")
		)
		(pad "B6" smd circle
			(at 0.999998 -0.249936)
			(size 0.2286 0.2286)
			(layers "F.Cu" "F.Mask" "F.Paste")
			(net "P12V_SCM_R")
		)
		(pad "B7" smd circle
			(at 1.500124 -0.249936)
			(size 0.2286 0.2286)
			(layers "F.Cu" "F.Mask" "F.Paste")
			(net "GND")
		)
		(pad "C1" smd circle
			(at -1.500124 0.249936)
			(size 0.2286 0.2286)
			(layers "F.Cu" "F.Mask" "F.Paste")
			(net "GND")
		)
		(pad "C2" smd circle
			(at -0.999998 0.249936)
			(size 0.2286 0.2286)
			(layers "F.Cu" "F.Mask" "F.Paste")
			(net "GND")
		)
		(pad "C3" smd circle
			(at -0.499872 0.249936)
			(size 0.2286 0.2286)
			(layers "F.Cu" "F.Mask" "F.Paste")
			(net "P12V_AUX")
		)
		(pad "C4" smd circle
			(at 0 0.249936)
			(size 0.2286 0.2286)
			(layers "F.Cu" "F.Mask" "F.Paste")
			(net "P12V_SCM_R")
		)
		(pad "C5" smd circle
			(at 0.499872 0.249936)
			(size 0.2286 0.2286)
			(layers "F.Cu" "F.Mask" "F.Paste")
			(net "P12V_AUX")
		)
		(pad "C6" smd circle
			(at 0.999998 0.249936)
			(size 0.2286 0.2286)
			(layers "F.Cu" "F.Mask" "F.Paste")
			(net "P12V_SCM_R")
		)
		(pad "C7" smd circle
			(at 1.500124 0.249936)
			(size 0.2286 0.2286)
			(layers "F.Cu" "F.Mask" "F.Paste")
			(net "P12V_SCM_FAULT_N")
		)
		(pad "D1" smd circle
			(at -1.500124 0.750062)
			(size 0.2286 0.2286)
			(layers "F.Cu" "F.Mask" "F.Paste")
			(net "P12V_SCM_REG")
		)
		(pad "D2" smd circle
			(at -0.999998 0.750062)
			(size 0.2286 0.2286)
			(layers "F.Cu" "F.Mask" "F.Paste")
			(net "P12V_SCM_UV")
		)
		(pad "D3" smd circle
			(at -0.499872 0.750062)
			(size 0.2286 0.2286)
			(layers "F.Cu" "F.Mask" "F.Paste")
			(net "P12V_SCM_OV")
		)
		(pad "D4" smd circle
			(at 0 0.750062)
			(size 0.2286 0.2286)
			(layers "F.Cu" "F.Mask" "F.Paste")
			(net "P12V_SCM_R")
		)
		(pad "D5" smd circle
			(at 0.499872 0.750062)
			(size 0.2286 0.2286)
			(layers "F.Cu" "F.Mask" "F.Paste")
			(net "P12V_AUX")
		)
		(pad "D6" smd circle
			(at 0.999998 0.750062)
			(size 0.2286 0.2286)
			(layers "F.Cu" "F.Mask" "F.Paste")
			(net "P12V_SCM_R")
		)
		(pad "D7" smd circle
			(at 1.500124 0.750062)
			(size 0.2286 0.2286)
			(layers "F.Cu" "F.Mask" "F.Paste")
			(net "P12V_SCM_PWRGD")
		)
	)
)
